(kicad_pcb
	(version 20221018)
	(generator pcbnew)
	(general
    (thickness 1.518)
  )
	(paper "A4")
	(title_block
    (title "Kria K26 Devboard")
    (date "2024-03-26")
    (rev "1.2.5")
    (comment 1 "www.antmicro.com")
    (comment 2 "Antmicro Ltd.")
		(comment 9 "footprints 305-314 of 660")
	)
	(layers
    (0 "F.Cu" mixed)
    (1 "In1.Cu" power)
    (2 "In2.Cu" mixed)
    (3 "In3.Cu" power)
    (4 "In4.Cu" mixed)
    (5 "In5.Cu" power)
    (6 "In6.Cu" mixed)
    (31 "B.Cu" power)
    (32 "B.Adhes" user "B.Adhesive")
    (33 "F.Adhes" user "F.Adhesive")
    (34 "B.Paste" user)
    (35 "F.Paste" user)
    (36 "B.SilkS" user "B.Silkscreen")
    (37 "F.SilkS" user "F.Silkscreen")
    (38 "B.Mask" user)
    (39 "F.Mask" user)
    (40 "Dwgs.User" user "User.Drawings")
    (41 "Cmts.User" user "User.Comments")
    (42 "Eco1.User" user "User.Eco1")
    (43 "Eco2.User" user "User.Eco2")
    (44 "Edge.Cuts" user)
    (45 "Margin" user)
    (46 "B.CrtYd" user "B.Courtyard")
    (47 "F.CrtYd" user "F.Courtyard")
    (48 "B.Fab" user)
    (49 "F.Fab" user)
  )
	(footprint "kria-k26-devboard-footprints:SOT-23-3" (layer "F.Cu")
    (at 149.5 65.125 180)
    (property "Author" "Antmicro")
    (property "License" "Apache-2.0")
    (property "MPN" "PJA3441_R1_00001")
    (property "Manufacturer" "Panjit")
    (property "Sheetfile" "usbc-socket.kicad_sch")
    (property "Sheetname" "USB-C socket")
    (property "ki_description" "MOSFET 40V P-Channel Enhancement Mode MOSFET")
    (attr smd)
    (fp_text reference "Q16" (at -0.19 -3.705 90) (layer "F.SilkS")
        (effects (font (size 0.7 0.7) (thickness 0.15)) (justify left bottom))
    )
    (fp_text value "PJA3441" (at -1.9 2.7 180) (layer "F.Fab") hide
        (effects (font (size 0.7 0.7) (thickness 0.15)) (justify left bottom))
    )
    (fp_text user "License: Apache-2.0" (at -1.8 6.8 180) (layer "F.Fab") hide
        (effects (font (size 0.7 0.7) (thickness 0.15)) (justify left bottom))
    )
    (fp_text user "${REFERENCE}" (at -1.837 4 180) (layer "F.Fab") hide
        (effects (font (size 0.7 0.7) (thickness 0.15)) (justify left bottom))
    )
    (fp_text user "Author: Antmicro" (at -1.837 5.3 180) (layer "F.Fab") hide
        (effects (font (size 0.7 0.7) (thickness 0.15)) (justify left bottom))
    )
    (fp_line (start -1.45 -1.35) (end -0.85 -1.35)
      (stroke (width 0.15) (type solid)) (layer "F.SilkS"))
    (fp_line (start -0.85 -1.35) (end -0.7 -1.5)
      (stroke (width 0.15) (type solid)) (layer "F.SilkS"))
    (fp_line (start -0.7 1.5) (end -0.7 1.35)
      (stroke (width 0.15) (type solid)) (layer "F.SilkS"))
    (fp_line (start 0.7 -1.5) (end -0.7 -1.5)
      (stroke (width 0.15) (type solid)) (layer "F.SilkS"))
    (fp_line (start 0.7 -0.4) (end 0.7 -1.5)
      (stroke (width 0.15) (type solid)) (layer "F.SilkS"))
    (fp_line (start 0.7 0.4) (end 0.7 1.5)
      (stroke (width 0.15) (type solid)) (layer "F.SilkS"))
    (fp_line (start 0.7 1.5) (end -0.7 1.5)
      (stroke (width 0.15) (type solid)) (layer "F.SilkS"))
    (fp_line (start -1.75 -0.5) (end -1.75 -1.4)
      (stroke (width 0.05) (type solid)) (layer "F.CrtYd"))
    (fp_line (start -1.75 0.5) (end -0.85 0.5)
      (stroke (width 0.05) (type solid)) (layer "F.CrtYd"))
    (fp_line (start -1.75 1.4) (end -1.75 0.5)
      (stroke (width 0.05) (type solid)) (layer "F.CrtYd"))
    (fp_line (start -0.9 -1.6) (end -0.9 -1.4)
      (stroke (width 0.05) (type solid)) (layer "F.CrtYd"))
    (fp_line (start -0.9 -1.6) (end 0.825 -1.6)
      (stroke (width 0.05) (type solid)) (layer "F.CrtYd"))
    (fp_line (start -0.9 -1.4) (end -1.75 -1.4)
      (stroke (width 0.05) (type solid)) (layer "F.CrtYd"))
    (fp_line (start -0.85 -0.5) (end -1.75 -0.5)
      (stroke (width 0.05) (type solid)) (layer "F.CrtYd"))
    (fp_line (start -0.85 0.5) (end -0.85 -0.5)
      (stroke (width 0.05) (type solid)) (layer "F.CrtYd"))
    (fp_line (start -0.85 1.4) (end -1.75 1.4)
      (stroke (width 0.05) (type solid)) (layer "F.CrtYd"))
    (fp_line (start -0.85 1.65) (end -0.85 1.4)
      (stroke (width 0.05) (type solid)) (layer "F.CrtYd"))
    (fp_line (start 0.825 -1.6) (end 0.825 -0.45)
      (stroke (width 0.05) (type solid)) (layer "F.CrtYd"))
    (fp_line (start 0.825 -0.45) (end 1.75 -0.45)
      (stroke (width 0.05) (type solid)) (layer "F.CrtYd"))
    (fp_line (start 0.85 0.45) (end 0.85 1.65)
      (stroke (width 0.05) (type solid)) (layer "F.CrtYd"))
    (fp_line (start 0.85 1.65) (end -0.85 1.65)
      (stroke (width 0.05) (type solid)) (layer "F.CrtYd"))
    (fp_line (start 1.75 -0.45) (end 1.75 0.45)
      (stroke (width 0.05) (type solid)) (layer "F.CrtYd"))
    (fp_line (start 1.75 0.45) (end 0.85 0.45)
      (stroke (width 0.05) (type solid)) (layer "F.CrtYd"))
    (fp_line (start -0.712 -1.325) (end -0.712 1.523)
      (stroke (width 0.15) (type solid)) (layer "F.Fab"))
    (fp_line (start -0.712 1.519) (end 0.688 1.519)
      (stroke (width 0.15) (type solid)) (layer "F.Fab"))
    (fp_line (start -0.437 -1.526) (end -0.712 -1.325)
      (stroke (width 0.15) (type solid)) (layer "F.Fab"))
    (fp_line (start -0.437 -1.526) (end 0.688 -1.526)
      (stroke (width 0.15) (type solid)) (layer "F.Fab"))
    (fp_line (start 0.688 1.519) (end 0.688 -1.52)
      (stroke (width 0.15) (type solid)) (layer "F.Fab"))
    (pad "1" smd roundrect (at -1.1 -0.951 180) (size 1 0.6) (layers "F.Cu" "F.Paste" "F.Mask") (roundrect_rratio 0.15)
      (net 433 "Net-(Q16-G)") (pinfunction "G") (pintype "bidirectional"))
    (pad "2" smd roundrect (at -1.1 0.949 180) (size 1 0.6) (layers "F.Cu" "F.Paste" "F.Mask") (roundrect_rratio 0.15)
      (net 265 "/Debug and JTAG/USBC_VBUS") (pinfunction "S") (pintype "bidirectional"))
    (pad "3" smd roundrect (at 1.1 -0.0005 180) (size 1 0.6) (layers "F.Cu" "F.Paste" "F.Mask") (roundrect_rratio 0.15)
      (net 228 "/Power Supply/Supply ORing/PD_VBUS") (pinfunction "D") (pintype "bidirectional"))
  )
	(footprint "kria-k26-devboard-footprints:Spacer_Drill4.45mm_H5mm_9774050960R" (layer "F.Cu")
    (at 160.206999 144.4435)
    (property "Author" "Antmicro")
    (property "License" "Apache-2.0")
    (property "MPN" "9774050960R")
    (property "Manufacturer" "Würth Elektronik")
    (property "Sheetfile" "k26_som.kicad_sch")
    (property "Sheetname" "Xilinx K26 SOM")
    (property "ki_description" "Spacer, SMT, Non Stop, Steel, Swage Round, 6 mm x 5 mm, 3.3 mm Internal, WA-SMST Series")
    (property "ki_keywords" "SPACER")
    (clearance 0.6)
    (attr smd)
    (fp_text reference "SP2" (at 0 -3.4) (layer "F.SilkS")
        (effects (font (size 0.7 0.7) (thickness 0.15)) (justify left bottom))
    )
    (fp_text value "Spacer_Drill4.45mm_H5mm_9774050960R" (at 0 4.2) (layer "F.Fab")
        (effects (font (size 0.7 0.7) (thickness 0.15)) (justify left bottom))
    )
    (fp_text user "License: Apache-2.0" (at -3.25 6.2) (layer "F.Fab") hide
        (effects (font (size 0.7 0.7) (thickness 0.15)) (justify left bottom))
    )
    (fp_text user "${REFERENCE}" (at -3.25 7.4) (layer "F.Fab") hide
        (effects (font (size 0.7 0.7) (thickness 0.15)) (justify left bottom))
    )
    (fp_text user "Author: Antmicro" (at -3.25 8.6) (layer "F.Fab") hide
        (effects (font (size 0.7 0.7) (thickness 0.15)) (justify left bottom))
    )
    (fp_circle (center 0 0) (end 3.25 0)
      (stroke (width 0.05) (type solid)) (fill none) (layer "F.CrtYd"))
    (fp_circle (center 0 0) (end 2.564 0)
      (stroke (width 0.15) (type solid)) (fill none) (layer "F.Fab"))
    (pad "1" thru_hole circle (at 0 0) (size 6 6) (drill 4.45) (layers "*.Cu" "*.Mask" "F.Paste")
      (net 1 "GND") (pintype "passive") (solder_paste_margin_ratio -0.05))
  )
	(footprint "kria-k26-devboard-footprints:USON-10_2.5x1mm_P0.5mm" (layer "F.Cu")
    (at 129.752 73.2805 90)
    (descr "USON-10 2.5x1mm_ Pitch 0.5mm")
    (tags "USON-10 2.5x1mm Pitch 0.5mm")
    (property "Author" "Antmicro")
    (property "License" "Apache-2.0")
    (property "MPN" "TPD4E05U06QDQARQ1")
    (property "Manufacturer" "Texas Instruments")
    (property "Sheetfile" "usb.kicad_sch")
    (property "Sheetname" "USB")
    (property "ki_description" "ESD protection")
    (property "ki_keywords" "SMT, DIODE, IC, TVS, ESD")
    (attr smd)
    (fp_text reference "U19" (at 0.018 -1.7 90) (layer "F.SilkS")
        (effects (font (size 0.7 0.7) (thickness 0.15)) (justify left bottom))
    )
    (fp_text value "TPD4E05U06QDQARQ1" (at 0.018 2.499 90) (layer "F.Fab")
        (effects (font (size 0.7 0.7) (thickness 0.15)) (justify left bottom))
    )
    (fp_text user "License: Apache-2.0" (at -0.802 6.9 90) (layer "F.Fab") hide
        (effects (font (size 0.7 0.7) (thickness 0.15)) (justify left bottom))
    )
    (fp_text user "Author: Antmicro" (at -0.802 5.7 90) (layer "F.Fab") hide
        (effects (font (size 0.7 0.7) (thickness 0.15)) (justify left bottom))
    )
    (fp_text user "${REFERENCE}" (at -0.802 4.498 90) (layer "F.Fab") hide
        (effects (font (size 0.7 0.7) (thickness 0.15)) (justify left bottom))
    )
    (fp_line (start 0.498 -1.401) (end -0.5 -1.401)
      (stroke (width 0.15) (type solid)) (layer "F.SilkS"))
    (fp_line (start 0.498 1.398) (end -0.5 1.398)
      (stroke (width 0.15) (type solid)) (layer "F.SilkS"))
    (fp_circle (center -0.68 -1.27) (end -0.63 -1.27)
      (stroke (width 0.15) (type solid)) (fill solid) (layer "F.SilkS"))
    (fp_rect (start -0.8 -1.5) (end 0.8 1.499)
      (stroke (width 0.05) (type solid)) (fill none) (layer "F.CrtYd"))
    (fp_line (start -0.5 -1) (end -0.5 1.249)
      (stroke (width 0.15) (type solid)) (layer "F.Fab"))
    (fp_line (start -0.5 1.249) (end 0.498 1.249)
      (stroke (width 0.15) (type solid)) (layer "F.Fab"))
    (fp_line (start -0.25 -1.25) (end -0.5 -1)
      (stroke (width 0.15) (type solid)) (layer "F.Fab"))
    (fp_line (start 0.498 -1.25) (end -0.25 -1.25)
      (stroke (width 0.15) (type solid)) (layer "F.Fab"))
    (fp_line (start 0.498 -1.25) (end 0.498 1.249)
      (stroke (width 0.15) (type solid)) (layer "F.Fab"))
    (pad "1" smd roundrect (at -0.387 -1) (size 0.25 0.55) (layers "F.Cu" "F.Paste" "F.Mask") (roundrect_rratio 0.25)
      (net 81 "/USB/USB2_RX_N") (pintype "passive"))
    (pad "2" smd roundrect (at -0.387 -0.5) (size 0.25 0.55) (layers "F.Cu" "F.Paste" "F.Mask") (roundrect_rratio 0.25)
      (net 82 "/USB/USB2_RX_P") (pintype "passive"))
    (pad "3" smd roundrect (at -0.387 0) (size 0.4 0.55) (layers "F.Cu" "F.Paste" "F.Mask") (roundrect_rratio 0.25)
      (net 1 "GND") (pintype "power_in"))
    (pad "4" smd roundrect (at -0.387 0.498) (size 0.25 0.55) (layers "F.Cu" "F.Paste" "F.Mask") (roundrect_rratio 0.25)
      (net 280 "/USB/USB2_TX_C_N") (pintype "passive"))
    (pad "5" smd roundrect (at -0.387 0.998) (size 0.25 0.55) (layers "F.Cu" "F.Paste" "F.Mask") (roundrect_rratio 0.25)
      (net 281 "/USB/USB2_TX_C_P") (pintype "passive"))
    (pad "6" smd roundrect (at 0.385 0.998) (size 0.25 0.55) (layers "F.Cu" "F.Paste" "F.Mask") (roundrect_rratio 0.25)
      (net 281 "/USB/USB2_TX_C_P") (pintype "passive"))
    (pad "7" smd roundrect (at 0.385 0.498) (size 0.25 0.55) (layers "F.Cu" "F.Paste" "F.Mask") (roundrect_rratio 0.25)
      (net 280 "/USB/USB2_TX_C_N") (pintype "passive"))
    (pad "8" smd roundrect (at 0.385 0) (size 0.4 0.55) (layers "F.Cu" "F.Paste" "F.Mask") (roundrect_rratio 0.25)
      (net 1 "GND") (pintype "passive"))
    (pad "9" smd roundrect (at 0.385 -0.5) (size 0.25 0.55) (layers "F.Cu" "F.Paste" "F.Mask") (roundrect_rratio 0.25)
      (net 82 "/USB/USB2_RX_P") (pintype "passive"))
    (pad "10" smd roundrect (at 0.385 -1) (size 0.25 0.55) (layers "F.Cu" "F.Paste" "F.Mask") (roundrect_rratio 0.25)
      (net 81 "/USB/USB2_RX_N") (pintype "passive"))
  )
	(footprint "kria-k26-devboard-footprints:TP_SMD_0.75mm" (layer "F.Cu")
    (at 145.55 110.95)
    (property "Author" "Antmicro")
    (property "License" "Apache-2.0")
    (property "MPN" "")
    (property "Manufacturer" "")
    (property "Sheetfile" "debug.kicad_sch")
    (property "Sheetname" "Debug and JTAG")
    (property "ki_description" "Test Point 0.75mm")
    (attr exclude_from_pos_files)
    (fp_text reference "TP29" (at 0.26 1.03) (layer "F.SilkS")
        (effects (font (size 0.7 0.7) (thickness 0.15)) (justify left bottom))
    )
    (fp_text value "TP_0.75mm_SMD" (at 0 1.2) (layer "F.Fab") hide
        (effects (font (size 0.7 0.7) (thickness 0.15)) (justify left bottom))
    )
    (fp_text user "${REFERENCE}" (at -0.4 2.7) (layer "F.Fab") hide
        (effects (font (size 0.7 0.7) (thickness 0.15)) (justify left bottom))
    )
    (fp_text user "License: Apache-2.0" (at -0.4 5.101) (layer "F.Fab") hide
        (effects (font (size 0.7 0.7) (thickness 0.15)) (justify left bottom))
    )
    (fp_text user "Author: Antmicro" (at -0.4 3.901) (layer "F.Fab") hide
        (effects (font (size 0.7 0.7) (thickness 0.15)) (justify left bottom))
    )
    (pad "1" smd circle (at 0 0) (size 0.75 0.75) (layers "F.Cu" "F.Mask")
      (net 136 "/Debug and JTAG/PD1_SVBUS") (pinfunction "1") (pintype "passive"))
  )
	(footprint "kria-k26-devboard-footprints:TP_SMD_0.75mm" (layer "F.Cu")
    (at 135.75 130.1)
    (property "Author" "Antmicro")
    (property "License" "Apache-2.0")
    (property "MPN" "")
    (property "Manufacturer" "")
    (property "Sheetfile" "debug.kicad_sch")
    (property "Sheetname" "Debug and JTAG")
    (property "ki_description" "Test Point 0.75mm")
    (attr exclude_from_pos_files)
    (fp_text reference "TP30" (at -3.02 0.37) (layer "F.SilkS")
        (effects (font (size 0.7 0.7) (thickness 0.15)) (justify left bottom))
    )
    (fp_text value "TP_0.75mm_SMD" (at 0 1.2) (layer "F.Fab") hide
        (effects (font (size 0.7 0.7) (thickness 0.15)) (justify left bottom))
    )
    (fp_text user "${REFERENCE}" (at -0.4 2.7) (layer "F.Fab") hide
        (effects (font (size 0.7 0.7) (thickness 0.15)) (justify left bottom))
    )
    (fp_text user "License: Apache-2.0" (at -0.4 5.101) (layer "F.Fab") hide
        (effects (font (size 0.7 0.7) (thickness 0.15)) (justify left bottom))
    )
    (fp_text user "Author: Antmicro" (at -0.4 3.901) (layer "F.Fab") hide
        (effects (font (size 0.7 0.7) (thickness 0.15)) (justify left bottom))
    )
    (pad "1" smd circle (at 0 0) (size 0.75 0.75) (layers "F.Cu" "F.Mask")
      (net 159 "/Debug and JTAG/~{FTDI_LS_OE}") (pinfunction "1") (pintype "passive"))
  )
	(footprint "kria-k26-devboard-footprints:TP_SMD_0.75mm" (layer "F.Cu")
    (at 135.3 129.08)
    (property "Author" "Antmicro")
    (property "License" "Apache-2.0")
    (property "MPN" "")
    (property "Manufacturer" "")
    (property "Sheetfile" "debug.kicad_sch")
    (property "Sheetname" "Debug and JTAG")
    (property "ki_description" "Test Point 0.75mm")
    (attr exclude_from_pos_files)
    (fp_text reference "TP31" (at -2.93 0.37) (layer "F.SilkS")
        (effects (font (size 0.7 0.7) (thickness 0.15)) (justify left bottom))
    )
    (fp_text value "TP_0.75mm_SMD" (at 0 1.2) (layer "F.Fab") hide
        (effects (font (size 0.7 0.7) (thickness 0.15)) (justify left bottom))
    )
    (fp_text user "Author: Antmicro" (at -0.4 3.901) (layer "F.Fab") hide
        (effects (font (size 0.7 0.7) (thickness 0.15)) (justify left bottom))
    )
    (fp_text user "${REFERENCE}" (at -0.4 2.7) (layer "F.Fab") hide
        (effects (font (size 0.7 0.7) (thickness 0.15)) (justify left bottom))
    )
    (fp_text user "License: Apache-2.0" (at -0.4 5.101) (layer "F.Fab") hide
        (effects (font (size 0.7 0.7) (thickness 0.15)) (justify left bottom))
    )
    (pad "1" smd circle (at 0 0) (size 0.75 0.75) (layers "F.Cu" "F.Mask")
      (net 220 "/Debug and JTAG/CONN_GND") (pinfunction "1") (pintype "passive"))
  )
	(footprint "kria-k26-devboard-footprints:TP_SMD_0.75mm" (layer "F.Cu")
    (at 134.75 124.9508)
    (property "Author" "Antmicro")
    (property "License" "Apache-2.0")
    (property "MPN" "")
    (property "Manufacturer" "")
    (property "Sheetfile" "debug.kicad_sch")
    (property "Sheetname" "Debug and JTAG")
    (property "ki_description" "Test Point 0.75mm")
    (attr exclude_from_pos_files)
    (fp_text reference "TP32" (at -3.02 0.3492) (layer "F.SilkS")
        (effects (font (size 0.7 0.7) (thickness 0.15)) (justify left bottom))
    )
    (fp_text value "TP_0.75mm_SMD" (at 0 1.2) (layer "F.Fab") hide
        (effects (font (size 0.7 0.7) (thickness 0.15)) (justify left bottom))
    )
    (fp_text user "License: Apache-2.0" (at -0.4 5.101) (layer "F.Fab") hide
        (effects (font (size 0.7 0.7) (thickness 0.15)) (justify left bottom))
    )
    (fp_text user "${REFERENCE}" (at -0.4 2.7) (layer "F.Fab") hide
        (effects (font (size 0.7 0.7) (thickness 0.15)) (justify left bottom))
    )
    (fp_text user "Author: Antmicro" (at -0.4 3.901) (layer "F.Fab") hide
        (effects (font (size 0.7 0.7) (thickness 0.15)) (justify left bottom))
    )
    (pad "1" smd circle (at 0 0) (size 0.75 0.75) (layers "F.Cu" "F.Mask")
      (net 160 "/Debug and JTAG/~{LS_OE}") (pinfunction "1") (pintype "passive"))
  )
	(footprint "kria-k26-devboard-footprints:TP_SMD_0.75mm" (layer "F.Cu")
    (at 167.525 137.25)
    (property "Author" "Antmicro")
    (property "License" "Apache-2.0")
    (property "MPN" "")
    (property "Manufacturer" "")
    (property "Sheetfile" "dc-dc-conventers.kicad_sch")
    (property "Sheetname" "DC/DC conventers")
    (property "ki_description" "Test Point 0.75mm")
    (attr exclude_from_pos_files)
    (fp_text reference "TP36" (at -2.965 0.97) (layer "F.SilkS")
        (effects (font (size 0.7 0.7) (thickness 0.15)) (justify left bottom))
    )
    (fp_text value "TP_0.75mm_SMD" (at 0 1.2) (layer "F.Fab") hide
        (effects (font (size 0.7 0.7) (thickness 0.15)) (justify left bottom))
    )
    (fp_text user "${REFERENCE}" (at -0.4 2.7) (layer "F.Fab") hide
        (effects (font (size 0.7 0.7) (thickness 0.15)) (justify left bottom))
    )
    (fp_text user "Author: Antmicro" (at -0.4 3.901) (layer "F.Fab") hide
        (effects (font (size 0.7 0.7) (thickness 0.15)) (justify left bottom))
    )
    (fp_text user "License: Apache-2.0" (at -0.4 5.101) (layer "F.Fab") hide
        (effects (font (size 0.7 0.7) (thickness 0.15)) (justify left bottom))
    )
    (pad "1" smd circle (at 0 0) (size 0.75 0.75) (layers "F.Cu" "F.Mask")
      (net 765 "/Power Supply/DC/DC conventers/PS_3V3_OUT") (pinfunction "1") (pintype "passive"))
  )
	(footprint "kria-k26-devboard-footprints:TP_SMD_0.75mm" (layer "F.Cu")
    (at 138.55 84.85)
    (property "Author" "Antmicro")
    (property "License" "Apache-2.0")
    (property "MPN" "")
    (property "Manufacturer" "")
    (property "Sheetfile" "dc-dc-conventers.kicad_sch")
    (property "Sheetname" "DC/DC conventers")
    (property "ki_description" "Test Point 0.75mm")
    (attr exclude_from_pos_files)
    (fp_text reference "TP37" (at -1.23 -0.43) (layer "F.SilkS")
        (effects (font (size 0.7 0.7) (thickness 0.15)) (justify left bottom))
    )
    (fp_text value "TP_0.75mm_SMD" (at 0 1.2) (layer "F.Fab") hide
        (effects (font (size 0.7 0.7) (thickness 0.15)) (justify left bottom))
    )
    (fp_text user "Author: Antmicro" (at -0.4 3.901) (layer "F.Fab") hide
        (effects (font (size 0.7 0.7) (thickness 0.15)) (justify left bottom))
    )
    (fp_text user "License: Apache-2.0" (at -0.4 5.101) (layer "F.Fab") hide
        (effects (font (size 0.7 0.7) (thickness 0.15)) (justify left bottom))
    )
    (fp_text user "${REFERENCE}" (at -0.4 2.7) (layer "F.Fab") hide
        (effects (font (size 0.7 0.7) (thickness 0.15)) (justify left bottom))
    )
    (pad "1" smd circle (at 0 0) (size 0.75 0.75) (layers "F.Cu" "F.Mask")
      (net 766 "/Power Supply/DC/DC conventers/PS_2V5_OUT") (pinfunction "1") (pintype "passive"))
  )
	(footprint "kria-k26-devboard-footprints:TP_SMD_0.75mm" (layer "F.Cu")
    (at 181.35 139.05)
    (property "Author" "Antmicro")
    (property "License" "Apache-2.0")
    (property "MPN" "")
    (property "Manufacturer" "")
    (property "Sheetfile" "dc-dc-conventers.kicad_sch")
    (property "Sheetname" "DC/DC conventers")
    (property "ki_description" "Test Point 0.75mm")
    (attr exclude_from_pos_files)
    (fp_text reference "TP41" (at -0.83 1.28) (layer "F.SilkS")
        (effects (font (size 0.7 0.7) (thickness 0.15)) (justify left bottom))
    )
    (fp_text value "TP_0.75mm_SMD" (at 0 1.2) (layer "F.Fab") hide
        (effects (font (size 0.7 0.7) (thickness 0.15)) (justify left bottom))
    )
    (fp_text user "${REFERENCE}" (at -0.4 2.7) (layer "F.Fab") hide
        (effects (font (size 0.7 0.7) (thickness 0.15)) (justify left bottom))
    )
    (fp_text user "Author: Antmicro" (at -0.4 3.901) (layer "F.Fab") hide
        (effects (font (size 0.7 0.7) (thickness 0.15)) (justify left bottom))
    )
    (fp_text user "License: Apache-2.0" (at -0.4 5.101) (layer "F.Fab") hide
        (effects (font (size 0.7 0.7) (thickness 0.15)) (justify left bottom))
    )
    (pad "1" smd circle (at 0 0) (size 0.75 0.75) (layers "F.Cu" "F.Mask")
      (net 770 "/Power Supply/DC/DC conventers/PL_3V3_OUT") (pinfunction "1") (pintype "passive"))
  )
)
